(kicad_pcb
	(version 20241229)
	(generator "pcbnew")
	(generator_version "9.0")
	(general
		(thickness 1.61)
		(legacy_teardrops no)
	)
	(paper "A3")
	(title_block
		(title "RDIMM DDR5 Tester")
		(date "2026-05-21")
		(rev "2.2.0")
		(company "Antmicro")
		(comment 9 "footprints 179-182 of 796")
	)
	(layers
		(0 "F.Cu" signal)
		(4 "In1.Cu" power)
		(6 "In2.Cu" mixed)
		(8 "In3.Cu" power)
		(10 "In4.Cu" mixed)
		(12 "In5.Cu" power)
		(14 "In6.Cu" mixed)
		(16 "In7.Cu" power)
		(18 "In8.Cu" power)
		(20 "In9.Cu" mixed)
		(22 "In10.Cu" power)
		(2 "B.Cu" signal)
		(9 "F.Adhes" user "F.Adhesive")
		(11 "B.Adhes" user "B.Adhesive")
		(13 "F.Paste" user)
		(15 "B.Paste" user)
		(5 "F.SilkS" user "F.Silkscreen")
		(7 "B.SilkS" user "B.Silkscreen")
		(1 "F.Mask" user)
		(3 "B.Mask" user)
		(17 "Dwgs.User" user "User.Drawings")
		(19 "Cmts.User" user "User.Comments")
		(21 "Eco1.User" user "User.Eco1")
		(23 "Eco2.User" user "User.Eco2")
		(25 "Edge.Cuts" user)
		(27 "Margin" user)
		(31 "F.CrtYd" user "F.Courtyard")
		(29 "B.CrtYd" user "B.Courtyard")
		(35 "F.Fab" user)
		(33 "B.Fab" user)
	)
	(footprint "antmicro-footprints:F_1206_3216Metric"
		(layer "F.Cu")
		(at 146.61 192.285 90)
		(property "Reference" "F2"
			(at 2.15 1.1 90)
			(layer "F.SilkS")
			(effects
				(font
					(size 0.7 0.7)
					(thickness 0.15)
				)
				(justify left bottom)
			)
		)
		(property "Value" "F_4A_1206"
			(at 0 2 90)
			(layer "F.Fab")
			(effects
				(font
					(size 0.7 0.7)
					(thickness 0.15)
				)
				(justify left bottom)
			)
		)
		(property "Datasheet" "https://www.littelfuse.com/media?resourcetype=datasheets&itemid=dbe9bcd7-6072-4adf-bf5b-d33e52a6b90f&filename=littelfuse-fuse-466-datasheet"
			(at 0 0 90)
			(layer "F.Fab")
			(hide yes)
			(effects
				(font
					(size 1.27 1.27)
					(thickness 0.15)
				)
			)
		)
		(property "Manufacturer" "Littelfuse"
			(at 0 0 90)
			(unlocked yes)
			(layer "F.Fab")
			(hide yes)
			(effects
				(font
					(size 1 1)
					(thickness 0.15)
				)
			)
		)
		(property "MPN" "0466004.NR "
			(at 0 0 90)
			(unlocked yes)
			(layer "F.Fab")
			(hide yes)
			(effects
				(font
					(size 1 1)
					(thickness 0.15)
				)
			)
		)
		(property "Author" "Antmicro"
			(at 0 0 90)
			(unlocked yes)
			(layer "F.Fab")
			(hide yes)
			(effects
				(font
					(size 1 1)
					(thickness 0.15)
				)
			)
		)
		(property "License" "Apache-2.0"
			(at 0 0 90)
			(unlocked yes)
			(layer "F.Fab")
			(hide yes)
			(effects
				(font
					(size 1 1)
					(thickness 0.15)
				)
			)
		)
		(sheetname "/Supply/")
		(sheetfile "supply.kicad_sch")
		(attr smd)
		(fp_line
			(start 0.8 -0.899)
			(end -0.8 -0.899)
			(stroke
				(width 0.15)
				(type solid)
			)
			(layer "F.SilkS")
		)
		(fp_line
			(start 0.8 0.901)
			(end -0.8 0.901)
			(stroke
				(width 0.15)
				(type solid)
			)
			(layer "F.SilkS")
		)
		(fp_rect
			(start -2.325 -1.15)
			(end 2.325 1.15)
			(stroke
				(width 0.05)
				(type default)
			)
			(fill no)
			(layer "F.CrtYd")
		)
		(fp_line
			(start 1.624 -0.861)
			(end 1.624 0.792)
			(stroke
				(width 0.15)
				(type solid)
			)
			(layer "F.Fab")
		)
		(fp_line
			(start -1.677 -0.861)
			(end 1.624 -0.861)
			(stroke
				(width 0.15)
				(type solid)
			)
			(layer "F.Fab")
		)
		(fp_line
			(start 1.624 0.792)
			(end -1.677 0.792)
			(stroke
				(width 0.15)
				(type solid)
			)
			(layer "F.Fab")
		)
		(fp_line
			(start -1.677 0.792)
			(end -1.677 -0.861)
			(stroke
				(width 0.15)
				(type solid)
			)
			(layer "F.Fab")
		)
		(fp_text user "Author: Antmicro"
			(at -1.95 6.4 90)
			(layer "F.Fab")
			(effects
				(font
					(size 0.7 0.7)
					(thickness 0.15)
				)
				(justify left bottom)
			)
		)
		(fp_text user "License: Apache-2.0"
			(at -1.95 5.2 90)
			(layer "F.Fab")
			(effects
				(font
					(size 0.7 0.7)
					(thickness 0.15)
				)
				(justify left bottom)
			)
		)
		(fp_text user "${REFERENCE}"
			(at -1.95 4 90)
			(layer "F.Fab")
			(effects
				(font
					(size 0.7 0.7)
					(thickness 0.15)
				)
				(justify left bottom)
			)
		)
		(pad "1" smd roundrect
			(at -1.5 0.001 90)
			(size 1.15 1.8)
			(layers "F.Cu" "F.Mask" "F.Paste")
			(roundrect_rratio 0.25)
			(net 10 "+12V")
			(pintype "passive")
		)
		(pad "2" smd roundrect
			(at 1.5 0.001 90)
			(size 1.15 1.8)
			(layers "F.Cu" "F.Mask" "F.Paste")
			(roundrect_rratio 0.25)
			(net 324 "/Supply/12V_PCIE_fused")
			(pintype "passive")
		)
	)
	(footprint "antmicro-footprints:SC70-3"
		(layer "F.Cu")
		(at 250.274499 143.3)
		(property "Reference" "Q11"
			(at 0.475501 1.04 90)
			(layer "F.SilkS")
			(effects
				(font
					(size 0.7 0.7)
					(thickness 0.15)
				)
				(justify left bottom)
			)
		)
		(property "Value" "BSS138PW"
			(at 0 2.3 0)
			(layer "F.Fab")
			(effects
				(font
					(size 0.7 0.7)
					(thickness 0.15)
				)
				(justify left bottom)
			)
		)
		(property "Datasheet" "https://assets.nexperia.com/documents/data-sheet/BSS138PW.pdf"
			(at 0 0 0)
			(layer "F.Fab")
			(hide yes)
			(effects
				(font
					(size 1.27 1.27)
					(thickness 0.15)
				)
			)
		)
		(property "MPN" "BSS138PW"
			(at 0 0 0)
			(unlocked yes)
			(layer "F.Fab")
			(hide yes)
			(effects
				(font
					(size 1 1)
					(thickness 0.15)
				)
			)
		)
		(property "Manufacturer" "Nexperia"
			(at 0 0 0)
			(unlocked yes)
			(layer "F.Fab")
			(hide yes)
			(effects
				(font
					(size 1 1)
					(thickness 0.15)
				)
			)
		)
		(property "Author" "Antmicro"
			(at 0 0 0)
			(unlocked yes)
			(layer "F.Fab")
			(hide yes)
			(effects
				(font
					(size 1 1)
					(thickness 0.15)
				)
			)
		)
		(property "License" "Apache-2.0"
			(at 0 0 0)
			(unlocked yes)
			(layer "F.Fab")
			(hide yes)
			(effects
				(font
					(size 1 1)
					(thickness 0.15)
				)
			)
		)
		(sheetname "/DDR5 RDIMM/")
		(sheetfile "ddr5-rdimm.kicad_sch")
		(attr smd)
		(fp_line
			(start -0.3 -1)
			(end 0.627 -0.999)
			(stroke
				(width 0.15)
				(type solid)
			)
			(layer "F.SilkS")
		)
		(fp_line
			(start -0.3 1)
			(end 0.627 1.001)
			(stroke
				(width 0.15)
				(type solid)
			)
			(layer "F.SilkS")
		)
		(fp_line
			(start 0.627 -0.6)
			(end 0.627 -0.999)
			(stroke
				(width 0.15)
				(type solid)
			)
			(layer "F.SilkS")
		)
		(fp_line
			(start 0.627 0.6)
			(end 0.627 1.001)
			(stroke
				(width 0.15)
				(type solid)
			)
			(layer "F.SilkS")
		)
		(fp_line
			(start -1.4 1)
			(end -1.4 -1)
			(stroke
				(width 0.05)
				(type solid)
			)
			(layer "F.CrtYd")
		)
		(fp_line
			(start -0.9 -1.3)
			(end -0.9 -1)
			(stroke
				(width 0.05)
				(type solid)
			)
			(layer "F.CrtYd")
		)
		(fp_line
			(start -0.9 -1.3)
			(end 0.9 -1.3)
			(stroke
				(width 0.05)
				(type solid)
			)
			(layer "F.CrtYd")
		)
		(fp_line
			(start -0.9 -1)
			(end -1.4 -1)
			(stroke
				(width 0.05)
				(type solid)
			)
			(layer "F.CrtYd")
		)
		(fp_line
			(start -0.9 1)
			(end -1.4 1)
			(stroke
				(width 0.05)
				(type solid)
			)
			(layer "F.CrtYd")
		)
		(fp_line
			(start -0.9 1.3)
			(end -0.9 1)
			(stroke
				(width 0.05)
				(type solid)
			)
			(layer "F.CrtYd")
		)
		(fp_line
			(start 0.9 -1.3)
			(end 0.9 -0.4)
			(stroke
				(width 0.05)
				(type solid)
			)
			(layer "F.CrtYd")
		)
		(fp_line
			(start 0.9 -0.4)
			(end 1.4 -0.4)
			(stroke
				(width 0.05)
				(type solid)
			)
			(layer "F.CrtYd")
		)
		(fp_line
			(start 0.9 0.4)
			(end 0.9 1.3)
			(stroke
				(width 0.05)
				(type solid)
			)
			(layer "F.CrtYd")
		)
		(fp_line
			(start 0.9 1.3)
			(end -0.9 1.3)
			(stroke
				(width 0.05)
				(type solid)
			)
			(layer "F.CrtYd")
		)
		(fp_line
			(start 1.4 -0.4)
			(end 1.4 0.4)
			(stroke
				(width 0.05)
				(type solid)
			)
			(layer "F.CrtYd")
		)
		(fp_line
			(start 1.4 0.4)
			(end 0.9 0.4)
			(stroke
				(width 0.05)
				(type solid)
			)
			(layer "F.CrtYd")
		)
		(fp_rect
			(start -0.623 -0.999)
			(end 0.627 1.001)
			(stroke
				(width 0.15)
				(type solid)
			)
			(fill no)
			(layer "F.Fab")
		)
		(fp_text user "Author: Antmicro"
			(at -1.45 5.782 0)
			(layer "F.Fab")
			(effects
				(font
					(size 0.7 0.7)
					(thickness 0.15)
				)
				(justify left bottom)
			)
		)
		(fp_text user "License: Apache-2.0"
			(at -1.45 6.782 0)
			(layer "F.Fab")
			(effects
				(font
					(size 0.7 0.7)
					(thickness 0.15)
				)
				(justify left bottom)
			)
		)
		(fp_text user "${REFERENCE}"
			(at -1.45 4.783 0)
			(layer "F.Fab")
			(effects
				(font
					(size 0.7 0.7)
					(thickness 0.15)
				)
				(justify left bottom)
			)
		)
		(pad "1" smd rect
			(at -1.051 -0.65 90)
			(size 0.6 0.6)
			(layers "F.Cu" "F.Mask" "F.Paste")
			(net 702 "HOT_SWAP_RED")
			(pinfunction "G")
			(pintype "passive")
		)
		(pad "2" smd rect
			(at -1.051 0.65 90)
			(size 0.6 0.6)
			(layers "F.Cu" "F.Mask" "F.Paste")
			(net 1 "GND")
			(pinfunction "S")
			(pintype "passive")
		)
		(pad "3" smd rect
			(at 1.05 0 90)
			(size 0.6 0.6)
			(layers "F.Cu" "F.Mask" "F.Paste")
			(net 283 "Net-(Q11-D)")
			(pinfunction "D")
			(pintype "passive")
		)
	)
	(footprint "antmicro-footprints:C_0402_1005Metric"
		(layer "F.Cu")
		(at 242.98 132.32 90)
		(descr "Capacitor SMD 0402")
		(tags "capacitor SMD 0402")
		(property "Reference" "C165"
			(at -1.78 1.62 90)
			(layer "F.SilkS")
			(effects
				(font
					(size 0.7 0.7)
					(thickness 0.15)
				)
				(justify left bottom)
			)
		)
		(property "Value" "C_100n_0402"
			(at -1.022927 2.155213 90)
			(layer "F.Fab")
			(effects
				(font
					(size 0.7 0.7)
					(thickness 0.15)
				)
				(justify left bottom)
			)
		)
		(property "Datasheet" "https://www.murata.com/products/productdetail?partno=GRM155R61H104KE14%23"
			(at 0 0 90)
			(layer "F.Fab")
			(hide yes)
			(effects
				(font
					(size 1.27 1.27)
					(thickness 0.15)
				)
			)
		)
		(property "Manufacturer" "Murata"
			(at 0 0 90)
			(unlocked yes)
			(layer "F.Fab")
			(hide yes)
			(effects
				(font
					(size 1 1)
					(thickness 0.15)
				)
			)
		)
		(property "MPN" "GRM155R61H104KE14D"
			(at 0 0 90)
			(unlocked yes)
			(layer "F.Fab")
			(hide yes)
			(effects
				(font
					(size 1 1)
					(thickness 0.15)
				)
			)
		)
		(property "Val" "100n"
			(at 0 0 90)
			(unlocked yes)
			(layer "F.Fab")
			(hide yes)
			(effects
				(font
					(size 1 1)
					(thickness 0.15)
				)
			)
		)
		(property "License" "Apache-2.0"
			(at 0 0 90)
			(unlocked yes)
			(layer "F.Fab")
			(hide yes)
			(effects
				(font
					(size 1 1)
					(thickness 0.15)
				)
			)
		)
		(property "Author" "Antmicro"
			(at 0 0 90)
			(unlocked yes)
			(layer "F.Fab")
			(hide yes)
			(effects
				(font
					(size 1 1)
					(thickness 0.15)
				)
			)
		)
		(property "Voltage" "50V"
			(at 0 0 90)
			(unlocked yes)
			(layer "F.Fab")
			(hide yes)
			(effects
				(font
					(size 1 1)
					(thickness 0.15)
				)
			)
		)
		(property "Dielectric" "X5R"
			(at 0 0 90)
			(unlocked yes)
			(layer "F.Fab")
			(hide yes)
			(effects
				(font
					(size 1 1)
					(thickness 0.15)
				)
			)
		)
		(sheetname "/I^{2}C + I3C/")
		(sheetfile "i2c.kicad_sch")
		(attr smd)
		(fp_rect
			(start -0.925 -0.47)
			(end 0.925 0.47)
			(stroke
				(width 0.05)
				(type default)
			)
			(fill no)
			(layer "F.CrtYd")
		)
		(fp_line
			(start 0.504 -0.25)
			(end 0.504 0.248)
			(stroke
				(width 0.15)
				(type solid)
			)
			(layer "F.Fab")
		)
		(fp_line
			(start -0.494 -0.25)
			(end 0.504 -0.25)
			(stroke
				(width 0.15)
				(type solid)
			)
			(layer "F.Fab")
		)
		(fp_line
			(start 0.504 0.248)
			(end -0.494 0.248)
			(stroke
				(width 0.15)
				(type solid)
			)
			(layer "F.Fab")
		)
		(fp_line
			(start -0.494 0.248)
			(end -0.494 -0.25)
			(stroke
				(width 0.15)
				(type solid)
			)
			(layer "F.Fab")
		)
		(fp_text user "License: Apache-2.0"
			(at -0.939 5.799 90)
			(layer "F.Fab")
			(effects
				(font
					(size 0.7 0.7)
					(thickness 0.15)
				)
				(justify left bottom)
			)
		)
		(fp_text user "Author: Antmicro"
			(at -0.939 3.399 90)
			(layer "F.Fab")
			(effects
				(font
					(size 0.7 0.7)
					(thickness 0.15)
				)
				(justify left bottom)
			)
		)
		(fp_text user "${REFERENCE}"
			(at -0.939 4.599 90)
			(layer "F.Fab")
			(effects
				(font
					(size 0.7 0.7)
					(thickness 0.15)
				)
				(justify left bottom)
			)
		)
		(pad "1" smd roundrect
			(at -0.48 0 90)
			(size 0.59 0.64)
			(layers "F.Cu" "F.Mask" "F.Paste")
			(roundrect_rratio 0.25)
			(net 151 "+3V3")
			(pintype "passive")
		)
		(pad "2" smd roundrect
			(at 0.48 0 90)
			(size 0.59 0.64)
			(layers "F.Cu" "F.Mask" "F.Paste")
			(roundrect_rratio 0.25)
			(net 1 "GND")
			(pintype "passive")
		)
	)
	(footprint "antmicro-footprints:USON-10_2.5x1mm_P0.5mm"
		(layer "F.Cu")
		(at 252.2 185.699)
		(descr "USON-10 2.5x1mm_ Pitch 0.5mm")
		(tags "USON-10 2.5x1mm Pitch 0.5mm")
		(property "Reference" "U33"
			(at -0.975 2.525 0)
			(layer "F.SilkS")
			(effects
				(font
					(size 0.7 0.7)
					(thickness 0.15)
				)
				(justify left bottom)
			)
		)
		(property "Value" "TPD4E05U06QDQARQ1"
			(at 0.018 2.499 0)
			(layer "F.Fab")
			(effects
				(font
					(size 0.7 0.7)
					(thickness 0.15)
				)
				(justify left bottom)
			)
		)
		(property "Datasheet" "https://www.ti.com/lit/ds/symlink/tpd4e05u06-q1.pdf?HQS=dis-mous-null-mousermode-dsf-pf-null-wwe&ts=1663591265741&ref_url=https%253A%252F%252Fwww.mouser.com%252F"
			(at 0 0 0)
			(layer "F.Fab")
			(hide yes)
			(effects
				(font
					(size 1.27 1.27)
					(thickness 0.15)
				)
			)
		)
		(property "Manufacturer" "Texas Instruments"
			(at 0 0 0)
			(unlocked yes)
			(layer "F.Fab")
			(hide yes)
			(effects
				(font
					(size 1 1)
					(thickness 0.15)
				)
			)
		)
		(property "MPN" "TPD4E05U06QDQARQ1"
			(at 0 0 0)
			(unlocked yes)
			(layer "F.Fab")
			(hide yes)
			(effects
				(font
					(size 1 1)
					(thickness 0.15)
				)
			)
		)
		(property "Author" "Antmicro"
			(at 0 0 0)
			(unlocked yes)
			(layer "F.Fab")
			(hide yes)
			(effects
				(font
					(size 1 1)
					(thickness 0.15)
				)
			)
		)
		(property "License" "Apache-2.0"
			(at 0 0 0)
			(unlocked yes)
			(layer "F.Fab")
			(hide yes)
			(effects
				(font
					(size 1 1)
					(thickness 0.15)
				)
			)
		)
		(sheetname "/I^{2}C + I3C/")
		(sheetfile "i2c.kicad_sch")
		(attr smd)
		(fp_line
			(start 0.498 -1.401)
			(end -0.5 -1.401)
			(stroke
				(width 0.15)
				(type solid)
			)
			(layer "F.SilkS")
		)
		(fp_line
			(start 0.498 1.398)
			(end -0.5 1.398)
			(stroke
				(width 0.15)
				(type solid)
			)
			(layer "F.SilkS")
		)
		(fp_circle
			(center -0.68 -1.27)
			(end -0.63 -1.27)
			(stroke
				(width 0.15)
				(type solid)
			)
			(fill yes)
			(layer "F.SilkS")
		)
		(fp_rect
			(start -0.8 -1.5)
			(end 0.8 1.499)
			(stroke
				(width 0.05)
				(type solid)
			)
			(fill no)
			(layer "F.CrtYd")
		)
		(fp_line
			(start -0.5 -1)
			(end -0.5 1.249)
			(stroke
				(width 0.15)
				(type solid)
			)
			(layer "F.Fab")
		)
		(fp_line
			(start -0.5 1.249)
			(end 0.498 1.249)
			(stroke
				(width 0.15)
				(type solid)
			)
			(layer "F.Fab")
		)
		(fp_line
			(start -0.25 -1.25)
			(end -0.5 -1)
			(stroke
				(width 0.15)
				(type solid)
			)
			(layer "F.Fab")
		)
		(fp_line
			(start 0.498 -1.25)
			(end -0.25 -1.25)
			(stroke
				(width 0.15)
				(type solid)
			)
			(layer "F.Fab")
		)
		(fp_line
			(start 0.498 -1.25)
			(end 0.498 1.249)
			(stroke
				(width 0.15)
				(type solid)
			)
			(layer "F.Fab")
		)
		(fp_text user "License: Apache-2.0"
			(at -0.802 6.9 0)
			(layer "F.Fab")
			(effects
				(font
					(size 0.7 0.7)
					(thickness 0.15)
				)
				(justify left bottom)
			)
		)
		(fp_text user "${REFERENCE}"
			(at -0.802 4.498 0)
			(layer "F.Fab")
			(effects
				(font
					(size 0.7 0.7)
					(thickness 0.15)
				)
				(justify left bottom)
			)
		)
		(fp_text user "Author: Antmicro"
			(at -0.802 5.7 0)
			(layer "F.Fab")
			(effects
				(font
					(size 0.7 0.7)
					(thickness 0.15)
				)
				(justify left bottom)
			)
		)
		(pad "1" smd roundrect
			(at -0.387 -1 270)
			(size 0.25 0.55)
			(layers "F.Cu" "F.Mask" "F.Paste")
			(roundrect_rratio 0.25)
			(net 151 "+3V3")
			(pintype "passive")
		)
		(pad "2" smd roundrect
			(at -0.387 -0.5 270)
			(size 0.25 0.55)
			(layers "F.Cu" "F.Mask" "F.Paste")
			(roundrect_rratio 0.25)
			(net 368 "/I^{2}C + I3C/I3C_EXT.SDA")
			(pintype "passive")
		)
		(pad "3" smd roundrect
			(at -0.387 0 270)
			(size 0.4 0.55)
			(layers "F.Cu" "F.Mask" "F.Paste")
			(roundrect_rratio 0.25)
			(net 1 "GND")
			(pintype "power_in")
		)
		(pad "4" smd roundrect
			(at -0.387 0.498 270)
			(size 0.25 0.55)
			(layers "F.Cu" "F.Mask" "F.Paste")
			(roundrect_rratio 0.25)
			(net 369 "/I^{2}C + I3C/I3C_EXT.SCL")
			(pintype "passive")
		)
		(pad "5" smd roundrect
			(at -0.387 0.998 270)
			(size 0.25 0.55)
			(layers "F.Cu" "F.Mask" "F.Paste")
			(roundrect_rratio 0.25)
			(net 817 "unconnected-(U33-Pad5)_1")
			(pintype "passive+no_connect")
		)
		(pad "6" smd roundrect
			(at 0.385 0.998 270)
			(size 0.25 0.55)
			(layers "F.Cu" "F.Mask" "F.Paste")
			(roundrect_rratio 0.25)
			(net 795 "unconnected-(U33-Pad5)")
			(pintype "passive+no_connect")
		)
		(pad "7" smd roundrect
			(at 0.385 0.498 270)
			(size 0.25 0.55)
			(layers "F.Cu" "F.Mask" "F.Paste")
			(roundrect_rratio 0.25)
			(net 369 "/I^{2}C + I3C/I3C_EXT.SCL")
			(pintype "passive")
		)
		(pad "8" smd roundrect
			(at 0.385 0 270)
			(size 0.4 0.55)
			(layers "F.Cu" "F.Mask" "F.Paste")
			(roundrect_rratio 0.25)
			(net 1 "GND")
			(pintype "passive")
		)
		(pad "9" smd roundrect
			(at 0.385 -0.5 270)
			(size 0.25 0.55)
			(layers "F.Cu" "F.Mask" "F.Paste")
			(roundrect_rratio 0.25)
			(net 368 "/I^{2}C + I3C/I3C_EXT.SDA")
			(pintype "passive")
		)
		(pad "10" smd roundrect
			(at 0.385 -1 270)
			(size 0.25 0.55)
			(layers "F.Cu" "F.Mask" "F.Paste")
			(roundrect_rratio 0.25)
			(net 151 "+3V3")
			(pintype "passive")
		)
	)
)
